# BASEBOARD_FAB2 (Tioga Pass) — schematic netlist excerpt (pin names and nets, part order shuffled) for the footprints in the layout excerpt that follows; sources: Cadence DE-HDL packaged netlist, KiCad conversion of Wiwynn_Tioga_Pass_MB.brd

R1L16  RES  49.9 1% CHIP  pkg 0402  page 196 : A = PWRGD_P3V3_R1 ; B = PWRGD_P3V3
RF8  RES  1.0K 0.1% CHIP  pkg 0402  page 206 : A = VR_PVCCIN_CPU1_AIREF2 ; B = ISENSE_PVCCIN_CPU1_PH2_IMON
C3G1  CAP_A  47UF 4V 20% X5R  pkg 0603V  page 225 : A = PVDDQ_GHJ ; B = GND

(kicad_pcb
	(version 20260206)
	(generator "pcbnew")
	(generator_version "10.0")
	(general
		(thickness 1.6)
		(legacy_teardrops no)
	)
	(paper "A4")
	(title_block
		(title "Wiwynn_Tioga_Pass_MB.brd")
		(comment 1 "Tioga Pass / footprints 344-346 of 4770")
	)
	(layers
		(0 "F.Cu" signal "TOP")
		(4 "In1.Cu" signal "L2GND")
		(6 "In2.Cu" signal "L3")
		(8 "In3.Cu" signal "L4GND")
		(10 "In4.Cu" signal "L5")
		(12 "In5.Cu" signal "L6GND")
		(14 "In6.Cu" signal "L7VCC")
		(16 "In7.Cu" signal "L8VCC")
		(18 "In8.Cu" signal "L9GND")
		(20 "In9.Cu" signal "L10")
		(22 "In10.Cu" signal "L11GND")
		(24 "In11.Cu" signal "L12")
		(26 "In12.Cu" signal "L13GND")
		(2 "B.Cu" signal "BOTTOM")
		(9 "F.Adhes" user "F.Adhesive")
		(11 "B.Adhes" user "B.Adhesive")
		(13 "F.Paste" user "Package Geometry/Pastemask Top")
		(15 "B.Paste" user "Package Geometry/Pastemask Bottom")
		(5 "F.SilkS" user "Ref Des/Silkscreen Top")
		(7 "B.SilkS" user "Ref Des/Silkscreen Bottom")
		(1 "F.Mask" user "Board Geometry/Soldermask Top")
		(3 "B.Mask" user "Board Geometry/Soldermask Bottom")
		(17 "Dwgs.User" user "User.Drawings")
		(19 "Cmts.User" user "User.Comments")
		(21 "Eco1.User" user "User.Eco1")
		(23 "Eco2.User" user "User.Eco2")
		(25 "Edge.Cuts" user "Board Geometry/Outline")
		(27 "Margin" user)
		(31 "F.CrtYd" user "Package Geometry/Place Bound Top")
		(29 "B.CrtYd" user "Package Geometry/Place Bound Bottom")
		(35 "F.Fab" user "Ref Des/Assembly Top")
		(33 "B.Fab" user "Ref Des/Assembly Bottom")
	)
	(footprint ""
		(layer "F.Cu")
		(at 474.472 -147.5105 180)
		(property "Reference" "R1L16"
			(at 0 0 180)
			(layer "F.SilkS")
			(hide yes)
			(effects
				(font
					(size 1.27 1.27)
				)
			)
		)
		(property "Value" ""
			(at 0 0 180)
			(layer "F.Fab")
			(effects
				(font
					(size 1.27 1.27)
				)
			)
		)
		(duplicate_pad_numbers_are_jumpers no)
		(fp_poly
			(pts
				(xy -0.2794 -0.1016) (xy 0.2794 -0.1016) (xy 0.2794 0.9906) (xy -0.2794 0.9906)
			)
			(stroke
				(width 0)
				(type default)
			)
			(fill no)
			(layer "F.CrtYd")
		)
		(fp_line
			(start 0.2794 0.9906)
			(end 0.2794 -0.1016)
			(stroke
				(width 0.1)
				(type default)
			)
			(layer "F.Fab")
		)
		(fp_line
			(start 0.2794 -0.1016)
			(end -0.2794 -0.1016)
			(stroke
				(width 0.1)
				(type default)
			)
			(layer "F.Fab")
		)
		(fp_line
			(start -0.2794 0.9906)
			(end 0.2794 0.9906)
			(stroke
				(width 0.1)
				(type default)
			)
			(layer "F.Fab")
		)
		(fp_line
			(start -0.2794 -0.1016)
			(end -0.2794 0.9906)
			(stroke
				(width 0.1)
				(type default)
			)
			(layer "F.Fab")
		)
		(pad "1" smd rect
			(at 0 0 180)
			(size 0.508 0.508)
			(layers "F.Cu" "F.Mask" "F.Paste")
			(net "PWRGD_P3V3_R1")
		)
		(pad "2" smd rect
			(at 0 0.889 180)
			(size 0.508 0.508)
			(layers "F.Cu" "F.Mask" "F.Paste")
			(net "PWRGD_P3V3")
		)
		(zone
			(layer "F.Cu")
			(hatch none 0.5)
			(connect_pads
				(clearance 0)
			)
			(min_thickness 0.25)
			(keepout
				(tracks not_allowed)
				(vias allowed)
				(pads allowed)
				(copperpour not_allowed)
				(footprints allowed)
			)
			(placement
				(enabled no)
				(sheetname "")
			)
			(fill
				(thermal_gap 0.5)
				(thermal_bridge_width 0.5)
				(island_removal_mode 0)
			)
			(polygon
				(pts
					(xy 474.726 -148.1455) (xy 474.218 -148.1455) (xy 474.218 -147.7645) (xy 474.726 -147.7645)
				)
			)
		)
		(zone
			(layer "F.Cu")
			(hatch none 0.5)
			(connect_pads
				(clearance 0)
			)
			(min_thickness 0.25)
			(keepout
				(tracks allowed)
				(vias not_allowed)
				(pads allowed)
				(copperpour not_allowed)
				(footprints allowed)
			)
			(placement
				(enabled no)
				(sheetname "")
			)
			(fill
				(thermal_gap 0.5)
				(thermal_bridge_width 0.5)
				(island_removal_mode 0)
			)
			(polygon
				(pts
					(xy 474.726 -147.7645) (xy 474.218 -147.7645) (xy 474.218 -148.1455) (xy 474.726 -148.1455)
				)
			)
		)
	)
	(footprint ""
		(layer "F.Cu")
		(at 107.8611 -12.954 90)
		(property "Reference" "C3G1"
			(at 1.848866 0.752348 90)
			(unlocked yes)
			(layer "F.SilkS")
			(effects
				(font
					(size 1.27 0.9652)
					(thickness 0.1524)
				)
			)
		)
		(property "Value" ""
			(at 0 0 90)
			(layer "F.Fab")
			(effects
				(font
					(size 1.27 1.27)
				)
			)
		)
		(duplicate_pad_numbers_are_jumpers no)
		(fp_rect
			(start -0.500126 1.598422)
			(end 0.500126 -0.201422)
			(stroke
				(width 0)
				(type default)
			)
			(fill no)
			(layer "F.CrtYd")
		)
		(fp_line
			(start 0.500126 -0.201422)
			(end 0.500126 1.598422)
			(stroke
				(width 0.1)
				(type default)
			)
			(layer "F.Fab")
		)
		(fp_line
			(start -0.500126 -0.201422)
			(end 0.500126 -0.201422)
			(stroke
				(width 0.1)
				(type default)
			)
			(layer "F.Fab")
		)
		(fp_line
			(start 0.500126 1.598422)
			(end -0.500126 1.598422)
			(stroke
				(width 0.1)
				(type default)
			)
			(layer "F.Fab")
		)
		(fp_line
			(start -0.500126 1.598422)
			(end -0.500126 -0.201422)
			(stroke
				(width 0.1)
				(type default)
			)
			(layer "F.Fab")
		)
		(pad "1" smd rect
			(at 0 0)
			(size 0.889 0.9906)
			(layers "F.Cu" "F.Mask" "F.Paste")
			(net "PVDDQ_GHJ")
		)
		(pad "2" smd rect
			(at 0 1.397)
			(size 0.889 0.9906)
			(layers "F.Cu" "F.Mask" "F.Paste")
			(net "GND")
		)
		(zone
			(layer "F.Cu")
			(hatch none 0.5)
			(connect_pads
				(clearance 0)
			)
			(min_thickness 0.25)
			(keepout
				(tracks allowed)
				(vias not_allowed)
				(pads allowed)
				(copperpour not_allowed)
				(footprints allowed)
			)
			(placement
				(enabled no)
				(sheetname "")
			)
			(fill
				(thermal_gap 0.5)
				(thermal_bridge_width 0.5)
				(island_removal_mode 0)
			)
			(polygon
				(pts
					(xy 108.8136 -12.4587) (xy 108.8136 -13.4493) (xy 108.3056 -13.4493) (xy 108.3056 -12.4587)
				)
			)
		)
		(zone
			(layer "F.Cu")
			(hatch none 0.5)
			(connect_pads
				(clearance 0)
			)
			(min_thickness 0.25)
			(keepout
				(tracks not_allowed)
				(vias allowed)
				(pads allowed)
				(copperpour not_allowed)
				(footprints allowed)
			)
			(placement
				(enabled no)
				(sheetname "")
			)
			(fill
				(thermal_gap 0.5)
				(thermal_bridge_width 0.5)
				(island_removal_mode 0)
			)
			(polygon
				(pts
					(xy 108.8136 -12.4587) (xy 108.8136 -13.4493) (xy 108.3056 -13.4493) (xy 108.3056 -12.4587)
				)
			)
		)
	)
	(footprint ""
		(layer "F.Cu")
		(at 24.007826 -87.841582 180)
		(property "Reference" "RF8"
			(at -0.8382 -0.67818 180)
			(unlocked yes)
			(layer "F.SilkS")
			(effects
				(font
					(size 0.4064 0.254)
					(thickness 0.1524)
				)
				(justify left)
			)
		)
		(property "Value" ""
			(at 0 0 180)
			(layer "F.Fab")
			(effects
				(font
					(size 1.27 1.27)
				)
			)
		)
		(duplicate_pad_numbers_are_jumpers no)
		(fp_poly
			(pts
				(xy -0.2794 -0.1016) (xy 0.2794 -0.1016) (xy 0.2794 0.9906) (xy -0.2794 0.9906)
			)
			(stroke
				(width 0)
				(type default)
			)
			(fill no)
			(layer "F.CrtYd")
		)
		(fp_line
			(start 0.2794 0.9906)
			(end 0.2794 -0.1016)
			(stroke
				(width 0.1)
				(type default)
			)
			(layer "F.Fab")
		)
		(fp_line
			(start 0.2794 -0.1016)
			(end -0.2794 -0.1016)
			(stroke
				(width 0.1)
				(type default)
			)
			(layer "F.Fab")
		)
		(fp_line
			(start -0.2794 0.9906)
			(end 0.2794 0.9906)
			(stroke
				(width 0.1)
				(type default)
			)
			(layer "F.Fab")
		)
		(fp_line
			(start -0.2794 -0.1016)
			(end -0.2794 0.9906)
			(stroke
				(width 0.1)
				(type default)
			)
			(layer "F.Fab")
		)
		(pad "1" smd rect
			(at 0 0 180)
			(size 0.508 0.508)
			(layers "F.Cu" "F.Mask" "F.Paste")
			(net "VR_PVCCIN_CPU1_AIREF2")
		)
		(pad "2" smd rect
			(at 0 0.889 180)
			(size 0.508 0.508)
			(layers "F.Cu" "F.Mask" "F.Paste")
			(net "ISENSE_PVCCIN_CPU1_PH2_IMON")
		)
		(zone
			(layer "F.Cu")
			(hatch none 0.5)
			(connect_pads
				(clearance 0)
			)
			(min_thickness 0.25)
			(keepout
				(tracks not_allowed)
				(vias allowed)
				(pads allowed)
				(copperpour not_allowed)
				(footprints allowed)
			)
			(placement
				(enabled no)
				(sheetname "")
			)
			(fill
				(thermal_gap 0.5)
				(thermal_bridge_width 0.5)
				(island_removal_mode 0)
			)
			(polygon
				(pts
					(xy 24.261826 -88.476582) (xy 23.753826 -88.476582) (xy 23.753826 -88.095582) (xy 24.261826 -88.095582)
				)
			)
		)
		(zone
			(layer "F.Cu")
			(hatch none 0.5)
			(connect_pads
				(clearance 0)
			)
			(min_thickness 0.25)
			(keepout
				(tracks allowed)
				(vias not_allowed)
				(pads allowed)
				(copperpour not_allowed)
				(footprints allowed)
			)
			(placement
				(enabled no)
				(sheetname "")
			)
			(fill
				(thermal_gap 0.5)
				(thermal_bridge_width 0.5)
				(island_removal_mode 0)
			)
			(polygon
				(pts
					(xy 24.261826 -88.095582) (xy 23.753826 -88.095582) (xy 23.753826 -88.476582) (xy 24.261826 -88.476582)
				)
			)
		)
	)
)
